(kicad_pcb
	(version 20260206)
	(generator "pcbnew")
	(generator_version "10.0")
	(general
		(thickness 1.6)
		(legacy_teardrops no)
	)
	(paper "A4")
	(title_block
		(title "01162023_DA0F0TEBIF0_F0T_Expander_BD_F_brd_V02_OCP.brd")
		(comment 1 "Grand Teton / footprints 8110-8117 of 9728")
	)
	(layers
		(0 "F.Cu" signal "TOP")
		(4 "In1.Cu" signal "GND")
		(6 "In2.Cu" signal "VCC")
		(8 "In3.Cu" signal "VCC1")
		(10 "In4.Cu" signal "GND1")
		(12 "In5.Cu" signal "IN1")
		(14 "In6.Cu" signal "GND2")
		(16 "In7.Cu" signal "IN2")
		(18 "In8.Cu" signal "GND3")
		(20 "In9.Cu" signal "IN3")
		(22 "In10.Cu" signal "GND4")
		(24 "In11.Cu" signal "IN4")
		(26 "In12.Cu" signal "GND5")
		(28 "In13.Cu" signal "IN5")
		(30 "In14.Cu" signal "GND6")
		(32 "In15.Cu" signal "IN6")
		(34 "In16.Cu" signal "GND7")
		(2 "B.Cu" signal "BOTTOM")
		(9 "F.Adhes" user "F.Adhesive")
		(11 "B.Adhes" user "B.Adhesive")
		(13 "F.Paste" user "Package Geometry/Pastemask Top")
		(15 "B.Paste" user "Package Geometry/Pastemask Bottom")
		(5 "F.SilkS" user "Ref Des/Silkscreen Top")
		(7 "B.SilkS" user "Ref Des/Silkscreen Bottom")
		(1 "F.Mask" user "Board Geometry/Soldermask Top")
		(3 "B.Mask" user "Board Geometry/Soldermask Bottom")
		(17 "Dwgs.User" user "User.Drawings")
		(19 "Cmts.User" user "User.Comments")
		(21 "Eco1.User" user "User.Eco1")
		(23 "Eco2.User" user "User.Eco2")
		(25 "Edge.Cuts" user "Board Geometry/Outline")
		(27 "Margin" user)
		(31 "F.CrtYd" user "Package Geometry/Place Bound Top")
		(29 "B.CrtYd" user "Package Geometry/Place Bound Bottom")
		(35 "F.Fab" user "Ref Des/Assembly Top")
		(33 "B.Fab" user "Ref Des/Assembly Bottom")
	)
	(footprint ""
		(layer "B.Cu")
		(at 207.110076 -222.65767 180)
		(property "Reference" "R6814"
			(at 0 0 0)
			(layer "B.SilkS")
			(hide yes)
			(effects
				(font
					(size 1.27 1.27)
				)
				(justify mirror)
			)
		)
		(property "Value" ""
			(at 0 0 0)
			(layer "B.Fab")
			(effects
				(font
					(size 1.27 1.27)
				)
				(justify mirror)
			)
		)
		(duplicate_pad_numbers_are_jumpers no)
		(fp_line
			(start 0.7874 0.4064)
			(end 0.7874 -0.4064)
			(stroke
				(width 0.1524)
				(type default)
			)
			(layer "B.SilkS")
		)
		(fp_line
			(start 0.7874 -0.4064)
			(end -0.7874 -0.4064)
			(stroke
				(width 0.1524)
				(type default)
			)
			(layer "B.SilkS")
		)
		(fp_line
			(start -0.7874 0.4064)
			(end 0.7874 0.4064)
			(stroke
				(width 0.1524)
				(type default)
			)
			(layer "B.SilkS")
		)
		(fp_line
			(start -0.7874 -0.4064)
			(end -0.7874 0.4064)
			(stroke
				(width 0.1524)
				(type default)
			)
			(layer "B.SilkS")
		)
		(fp_line
			(start 0.67945 0.3048)
			(end 0.67945 -0.305054)
			(stroke
				(width 0.1)
				(type default)
			)
			(layer "B.Fab")
		)
		(fp_line
			(start 0.67945 -0.305054)
			(end 0.12065 -0.305054)
			(stroke
				(width 0.1)
				(type default)
			)
			(layer "B.Fab")
		)
		(fp_line
			(start 0.12065 0.3048)
			(end 0.67945 0.3048)
			(stroke
				(width 0.1)
				(type default)
			)
			(layer "B.Fab")
		)
		(fp_line
			(start 0.12065 0.2794)
			(end 0.12065 0.3048)
			(stroke
				(width 0.1)
				(type default)
			)
			(layer "B.Fab")
		)
		(fp_line
			(start 0.12065 -0.2794)
			(end -0.12065 -0.2794)
			(stroke
				(width 0.1)
				(type default)
			)
			(layer "B.Fab")
		)
		(fp_line
			(start 0.12065 -0.305054)
			(end 0.12065 -0.2794)
			(stroke
				(width 0.1)
				(type default)
			)
			(layer "B.Fab")
		)
		(fp_line
			(start -0.120396 0.3048)
			(end -0.120396 0.2794)
			(stroke
				(width 0.1)
				(type default)
			)
			(layer "B.Fab")
		)
		(fp_line
			(start -0.120396 0.2794)
			(end 0.12065 0.2794)
			(stroke
				(width 0.1)
				(type default)
			)
			(layer "B.Fab")
		)
		(fp_line
			(start -0.12065 -0.2794)
			(end -0.12065 -0.3048)
			(stroke
				(width 0.1)
				(type default)
			)
			(layer "B.Fab")
		)
		(fp_line
			(start -0.12065 -0.3048)
			(end -0.67945 -0.3048)
			(stroke
				(width 0.1)
				(type default)
			)
			(layer "B.Fab")
		)
		(fp_line
			(start -0.67945 0.3048)
			(end -0.120396 0.3048)
			(stroke
				(width 0.1)
				(type default)
			)
			(layer "B.Fab")
		)
		(fp_line
			(start -0.67945 -0.3048)
			(end -0.67945 0.3048)
			(stroke
				(width 0.1)
				(type default)
			)
			(layer "B.Fab")
		)
		(pad "1" smd circle
			(at 0.40005 0)
			(size 0 0)
			(layers "B.Cu" "B.Mask" "B.Paste")
			(net "BOARD_TYPE_1_ADC_R")
		)
		(pad "2" smd circle
			(at -0.40005 0)
			(size 0 0)
			(layers "B.Cu" "B.Mask" "B.Paste")
			(net "P3V3_AUX")
		)
	)
	(footprint ""
		(layer "B.Cu")
		(at 355.81463 -303.649634 -90)
		(property "Reference" "PC199"
			(at 0 0 90)
			(layer "B.SilkS")
			(hide yes)
			(effects
				(font
					(size 1.27 1.27)
				)
				(justify mirror)
			)
		)
		(property "Value" ""
			(at 0 0 90)
			(layer "B.Fab")
			(effects
				(font
					(size 1.27 1.27)
				)
				(justify mirror)
			)
		)
		(duplicate_pad_numbers_are_jumpers no)
		(fp_line
			(start -1.524 0.762)
			(end 1.524 0.762)
			(stroke
				(width 0.1524)
				(type default)
			)
			(layer "B.SilkS")
		)
		(fp_line
			(start 1.524 0.762)
			(end 1.524 -0.762)
			(stroke
				(width 0.1524)
				(type default)
			)
			(layer "B.SilkS")
		)
		(fp_line
			(start -1.524 -0.762)
			(end -1.524 0.762)
			(stroke
				(width 0.1524)
				(type default)
			)
			(layer "B.SilkS")
		)
		(fp_line
			(start 1.524 -0.762)
			(end -1.524 -0.762)
			(stroke
				(width 0.1524)
				(type default)
			)
			(layer "B.SilkS")
		)
		(fp_line
			(start -1.1049 0.724916)
			(end -1.1049 -0.724916)
			(stroke
				(width 0.1)
				(type default)
			)
			(layer "B.Fab")
		)
		(fp_line
			(start 1.1049 0.724916)
			(end -1.1049 0.724916)
			(stroke
				(width 0.1)
				(type default)
			)
			(layer "B.Fab")
		)
		(fp_line
			(start -1.1049 -0.724916)
			(end 1.1049 -0.724916)
			(stroke
				(width 0.1)
				(type default)
			)
			(layer "B.Fab")
		)
		(fp_line
			(start 1.1049 -0.724916)
			(end 1.1049 0.724916)
			(stroke
				(width 0.1)
				(type default)
			)
			(layer "B.Fab")
		)
		(pad "1" smd rect
			(at 0.889 0 270)
			(size 1.016 1.27)
			(layers "B.Cu" "B.Mask" "B.Paste")
			(net "P0V8_PEX3")
		)
		(pad "2" smd rect
			(at -0.889 0 270)
			(size 1.016 1.27)
			(layers "B.Cu" "B.Mask" "B.Paste")
			(net "GND")
		)
	)
	(footprint ""
		(layer "B.Cu")
		(at 281.399742 -292.574726 180)
		(property "Reference" "C1615"
			(at 0 0 0)
			(layer "B.SilkS")
			(hide yes)
			(effects
				(font
					(size 1.27 1.27)
				)
				(justify mirror)
			)
		)
		(property "Value" ""
			(at 0 0 0)
			(layer "B.Fab")
			(effects
				(font
					(size 1.27 1.27)
				)
				(justify mirror)
			)
		)
		(duplicate_pad_numbers_are_jumpers no)
		(fp_line
			(start 0.299974 0.150114)
			(end 0.299974 -0.150114)
			(stroke
				(width 0.1)
				(type default)
			)
			(layer "B.Fab")
		)
		(fp_line
			(start 0.299974 -0.150114)
			(end -0.299974 -0.150114)
			(stroke
				(width 0.1)
				(type default)
			)
			(layer "B.Fab")
		)
		(fp_line
			(start -0.299974 0.150114)
			(end 0.299974 0.150114)
			(stroke
				(width 0.1)
				(type default)
			)
			(layer "B.Fab")
		)
		(fp_line
			(start -0.299974 -0.150114)
			(end -0.299974 0.150114)
			(stroke
				(width 0.1)
				(type default)
			)
			(layer "B.Fab")
		)
		(pad "1" smd rect
			(at 0.2667 0)
			(size 0.3048 0.381)
			(layers "B.Cu" "B.Mask" "B.Paste")
			(net "P0V8_PEX2")
		)
		(pad "2" smd rect
			(at -0.2667 0)
			(size 0.3048 0.381)
			(layers "B.Cu" "B.Mask" "B.Paste")
			(net "GND")
		)
	)
	(footprint ""
		(layer "B.Cu")
		(at 348.119954 -260.400546 -90)
		(property "Reference" "PR144"
			(at 0 0 90)
			(layer "B.SilkS")
			(hide yes)
			(effects
				(font
					(size 1.27 1.27)
				)
				(justify mirror)
			)
		)
		(property "Value" ""
			(at 0 0 90)
			(layer "B.Fab")
			(effects
				(font
					(size 1.27 1.27)
				)
				(justify mirror)
			)
		)
		(duplicate_pad_numbers_are_jumpers no)
		(fp_line
			(start -0.7874 0.4064)
			(end 0.7874 0.4064)
			(stroke
				(width 0.1524)
				(type default)
			)
			(layer "B.SilkS")
		)
		(fp_line
			(start 0.7874 0.4064)
			(end 0.7874 -0.4064)
			(stroke
				(width 0.1524)
				(type default)
			)
			(layer "B.SilkS")
		)
		(fp_line
			(start -0.7874 -0.4064)
			(end -0.7874 0.4064)
			(stroke
				(width 0.1524)
				(type default)
			)
			(layer "B.SilkS")
		)
		(fp_line
			(start 0.7874 -0.4064)
			(end -0.7874 -0.4064)
			(stroke
				(width 0.1524)
				(type default)
			)
			(layer "B.SilkS")
		)
		(fp_line
			(start -0.67945 0.3048)
			(end -0.120396 0.3048)
			(stroke
				(width 0.1)
				(type default)
			)
			(layer "B.Fab")
		)
		(fp_line
			(start -0.120396 0.3048)
			(end -0.120396 0.2794)
			(stroke
				(width 0.1)
				(type default)
			)
			(layer "B.Fab")
		)
		(fp_line
			(start 0.12065 0.3048)
			(end 0.67945 0.3048)
			(stroke
				(width 0.1)
				(type default)
			)
			(layer "B.Fab")
		)
		(fp_line
			(start 0.67945 0.3048)
			(end 0.67945 -0.305054)
			(stroke
				(width 0.1)
				(type default)
			)
			(layer "B.Fab")
		)
		(fp_line
			(start -0.120396 0.2794)
			(end 0.12065 0.2794)
			(stroke
				(width 0.1)
				(type default)
			)
			(layer "B.Fab")
		)
		(fp_line
			(start 0.12065 0.2794)
			(end 0.12065 0.3048)
			(stroke
				(width 0.1)
				(type default)
			)
			(layer "B.Fab")
		)
		(fp_line
			(start -0.12065 -0.2794)
			(end -0.12065 -0.3048)
			(stroke
				(width 0.1)
				(type default)
			)
			(layer "B.Fab")
		)
		(fp_line
			(start 0.12065 -0.2794)
			(end -0.12065 -0.2794)
			(stroke
				(width 0.1)
				(type default)
			)
			(layer "B.Fab")
		)
		(fp_line
			(start -0.67945 -0.3048)
			(end -0.67945 0.3048)
			(stroke
				(width 0.1)
				(type default)
			)
			(layer "B.Fab")
		)
		(fp_line
			(start -0.12065 -0.3048)
			(end -0.67945 -0.3048)
			(stroke
				(width 0.1)
				(type default)
			)
			(layer "B.Fab")
		)
		(fp_line
			(start 0.12065 -0.305054)
			(end 0.12065 -0.2794)
			(stroke
				(width 0.1)
				(type default)
			)
			(layer "B.Fab")
		)
		(fp_line
			(start 0.67945 -0.305054)
			(end 0.12065 -0.305054)
			(stroke
				(width 0.1)
				(type default)
			)
			(layer "B.Fab")
		)
		(pad "1" smd circle
			(at 0.40005 0 90)
			(size 0 0)
			(layers "B.Cu" "B.Mask" "B.Paste")
			(net "P0V8_PEX2_TSEN_R")
		)
		(pad "2" smd circle
			(at -0.40005 0 90)
			(size 0 0)
			(layers "B.Cu" "B.Mask" "B.Paste")
			(net "P0V8_PEX2_TSEN")
		)
	)
	(footprint ""
		(layer "B.Cu")
		(at 58.170064 -305.399948 -90)
		(property "Reference" "C2967"
			(at 0 0 90)
			(layer "B.SilkS")
			(hide yes)
			(effects
				(font
					(size 1.27 1.27)
				)
				(justify mirror)
			)
		)
		(property "Value" ""
			(at 0 0 90)
			(layer "B.Fab")
			(effects
				(font
					(size 1.27 1.27)
				)
				(justify mirror)
			)
		)
		(duplicate_pad_numbers_are_jumpers no)
		(fp_line
			(start -0.299974 0.150114)
			(end 0.299974 0.150114)
			(stroke
				(width 0.1)
				(type default)
			)
			(layer "B.Fab")
		)
		(fp_line
			(start 0.299974 0.150114)
			(end 0.299974 -0.150114)
			(stroke
				(width 0.1)
				(type default)
			)
			(layer "B.Fab")
		)
		(fp_line
			(start -0.299974 -0.150114)
			(end -0.299974 0.150114)
			(stroke
				(width 0.1)
				(type default)
			)
			(layer "B.Fab")
		)
		(fp_line
			(start 0.299974 -0.150114)
			(end -0.299974 -0.150114)
			(stroke
				(width 0.1)
				(type default)
			)
			(layer "B.Fab")
		)
		(pad "1" smd rect
			(at 0.2667 0 90)
			(size 0.3048 0.381)
			(layers "B.Cu" "B.Mask" "B.Paste")
			(net "P1V25_SERDES_VDDPLL_PEX0")
		)
		(pad "2" smd rect
			(at -0.2667 0 90)
			(size 0.3048 0.381)
			(layers "B.Cu" "B.Mask" "B.Paste")
			(net "GND")
		)
	)
	(footprint ""
		(layer "B.Cu")
		(at 11.1379 -264.586466 180)
		(property "Reference" "R6128"
			(at 0 0 0)
			(layer "B.SilkS")
			(hide yes)
			(effects
				(font
					(size 1.27 1.27)
				)
				(justify mirror)
			)
		)
		(property "Value" ""
			(at 0 0 0)
			(layer "B.Fab")
			(effects
				(font
					(size 1.27 1.27)
				)
				(justify mirror)
			)
		)
		(duplicate_pad_numbers_are_jumpers no)
		(fp_line
			(start 2.576322 1.1303)
			(end 2.576322 -1.1303)
			(stroke
				(width 0.1524)
				(type default)
			)
			(layer "B.SilkS")
		)
		(fp_line
			(start 2.576322 -1.1303)
			(end -2.576322 -1.1303)
			(stroke
				(width 0.1524)
				(type default)
			)
			(layer "B.SilkS")
		)
		(fp_line
			(start -2.576322 1.1303)
			(end 2.576322 1.1303)
			(stroke
				(width 0.1524)
				(type default)
			)
			(layer "B.SilkS")
		)
		(fp_line
			(start -2.576322 -1.1303)
			(end -2.576322 1.1303)
			(stroke
				(width 0.1524)
				(type default)
			)
			(layer "B.SilkS")
		)
		(fp_line
			(start 1.649984 0.899922)
			(end -1.649984 0.899922)
			(stroke
				(width 0.1)
				(type default)
			)
			(layer "B.Fab")
		)
		(fp_line
			(start 1.649984 -0.899922)
			(end 1.649984 0.899922)
			(stroke
				(width 0.1)
				(type default)
			)
			(layer "B.Fab")
		)
		(fp_line
			(start -1.649984 0.899922)
			(end -1.649984 -0.899922)
			(stroke
				(width 0.1)
				(type default)
			)
			(layer "B.Fab")
		)
		(fp_line
			(start -1.649984 -0.899922)
			(end 1.649984 -0.899922)
			(stroke
				(width 0.1)
				(type default)
			)
			(layer "B.Fab")
		)
		(pad "1A" smd rect
			(at 1.700022 0)
			(size 1.4986 2.0066)
			(layers "B.Cu" "B.Mask" "B.Paste")
			(net "P1V25_PEX0")
		)
		(pad "1B" smd rect
			(at 1.077722 0)
			(size 0.254 0.508)
			(layers "B.Cu" "B.Mask" "B.Paste")
			(net "P1V25_PEX0")
		)
		(pad "2A" smd rect
			(at -1.700022 0)
			(size 1.4986 2.0066)
			(layers "B.Cu" "B.Mask" "B.Paste")
			(net "P1V25_SERDES_VDDPLL_PEX0")
		)
		(pad "2B" smd rect
			(at -1.077722 0)
			(size 0.254 0.508)
			(layers "B.Cu" "B.Mask" "B.Paste")
			(net "P1V25_SERDES_VDDPLL_PEX0")
		)
	)
	(footprint ""
		(layer "B.Cu")
		(at 346.075 -233.553 90)
		(property "Reference" "R3578"
			(at 0 0 90)
			(layer "B.SilkS")
			(hide yes)
			(effects
				(font
					(size 1.27 1.27)
				)
				(justify mirror)
			)
		)
		(property "Value" ""
			(at 0 0 90)
			(layer "B.Fab")
			(effects
				(font
					(size 1.27 1.27)
				)
				(justify mirror)
			)
		)
		(duplicate_pad_numbers_are_jumpers no)
		(fp_line
			(start 0.7874 -0.4064)
			(end -0.7874 -0.4064)
			(stroke
				(width 0.1524)
				(type default)
			)
			(layer "B.SilkS")
		)
		(fp_line
			(start -0.7874 -0.4064)
			(end -0.7874 0.4064)
			(stroke
				(width 0.1524)
				(type default)
			)
			(layer "B.SilkS")
		)
		(fp_line
			(start 0.7874 0.4064)
			(end 0.7874 -0.4064)
			(stroke
				(width 0.1524)
				(type default)
			)
			(layer "B.SilkS")
		)
		(fp_line
			(start -0.7874 0.4064)
			(end 0.7874 0.4064)
			(stroke
				(width 0.1524)
				(type default)
			)
			(layer "B.SilkS")
		)
		(fp_line
			(start 0.67945 -0.305054)
			(end 0.12065 -0.305054)
			(stroke
				(width 0.1)
				(type default)
			)
			(layer "B.Fab")
		)
		(fp_line
			(start 0.12065 -0.305054)
			(end 0.12065 -0.2794)
			(stroke
				(width 0.1)
				(type default)
			)
			(layer "B.Fab")
		)
		(fp_line
			(start -0.12065 -0.3048)
			(end -0.67945 -0.3048)
			(stroke
				(width 0.1)
				(type default)
			)
			(layer "B.Fab")
		)
		(fp_line
			(start -0.67945 -0.3048)
			(end -0.67945 0.3048)
			(stroke
				(width 0.1)
				(type default)
			)
			(layer "B.Fab")
		)
		(fp_line
			(start 0.12065 -0.2794)
			(end -0.12065 -0.2794)
			(stroke
				(width 0.1)
				(type default)
			)
			(layer "B.Fab")
		)
		(fp_line
			(start -0.12065 -0.2794)
			(end -0.12065 -0.3048)
			(stroke
				(width 0.1)
				(type default)
			)
			(layer "B.Fab")
		)
		(fp_line
			(start 0.12065 0.2794)
			(end 0.12065 0.3048)
			(stroke
				(width 0.1)
				(type default)
			)
			(layer "B.Fab")
		)
		(fp_line
			(start -0.120396 0.2794)
			(end 0.12065 0.2794)
			(stroke
				(width 0.1)
				(type default)
			)
			(layer "B.Fab")
		)
		(fp_line
			(start 0.67945 0.3048)
			(end 0.67945 -0.305054)
			(stroke
				(width 0.1)
				(type default)
			)
			(layer "B.Fab")
		)
		(fp_line
			(start 0.12065 0.3048)
			(end 0.67945 0.3048)
			(stroke
				(width 0.1)
				(type default)
			)
			(layer "B.Fab")
		)
		(fp_line
			(start -0.120396 0.3048)
			(end -0.120396 0.2794)
			(stroke
				(width 0.1)
				(type default)
			)
			(layer "B.Fab")
		)
		(fp_line
			(start -0.67945 0.3048)
			(end -0.120396 0.3048)
			(stroke
				(width 0.1)
				(type default)
			)
			(layer "B.Fab")
		)
		(pad "1" smd circle
			(at 0.40005 0 270)
			(size 0 0)
			(layers "B.Cu" "B.Mask" "B.Paste")
			(net "SSD6_PWRDIS_R")
		)
		(pad "2" smd circle
			(at -0.40005 0 270)
			(size 0 0)
			(layers "B.Cu" "B.Mask" "B.Paste")
			(net "SSD6_PWRDIS")
		)
	)
	(footprint ""
		(layer "B.Cu")
		(at 222.322644 -231.225598 -90)
		(property "Reference" "R1477"
			(at 0 0 90)
			(layer "B.SilkS")
			(hide yes)
			(effects
				(font
					(size 1.27 1.27)
				)
				(justify mirror)
			)
		)
		(property "Value" ""
			(at 0 0 90)
			(layer "B.Fab")
			(effects
				(font
					(size 1.27 1.27)
				)
				(justify mirror)
			)
		)
		(duplicate_pad_numbers_are_jumpers no)
		(fp_line
			(start -0.7874 0.4064)
			(end 0.7874 0.4064)
			(stroke
				(width 0.1524)
				(type default)
			)
			(layer "B.SilkS")
		)
		(fp_line
			(start 0.7874 0.4064)
			(end 0.7874 -0.4064)
			(stroke
				(width 0.1524)
				(type default)
			)
			(layer "B.SilkS")
		)
		(fp_line
			(start -0.7874 -0.4064)
			(end -0.7874 0.4064)
			(stroke
				(width 0.1524)
				(type default)
			)
			(layer "B.SilkS")
		)
		(fp_line
			(start 0.7874 -0.4064)
			(end -0.7874 -0.4064)
			(stroke
				(width 0.1524)
				(type default)
			)
			(layer "B.SilkS")
		)
		(fp_line
			(start -0.67945 0.3048)
			(end -0.120396 0.3048)
			(stroke
				(width 0.1)
				(type default)
			)
			(layer "B.Fab")
		)
		(fp_line
			(start -0.120396 0.3048)
			(end -0.120396 0.2794)
			(stroke
				(width 0.1)
				(type default)
			)
			(layer "B.Fab")
		)
		(fp_line
			(start 0.12065 0.3048)
			(end 0.67945 0.3048)
			(stroke
				(width 0.1)
				(type default)
			)
			(layer "B.Fab")
		)
		(fp_line
			(start 0.67945 0.3048)
			(end 0.67945 -0.305054)
			(stroke
				(width 0.1)
				(type default)
			)
			(layer "B.Fab")
		)
		(fp_line
			(start -0.120396 0.2794)
			(end 0.12065 0.2794)
			(stroke
				(width 0.1)
				(type default)
			)
			(layer "B.Fab")
		)
		(fp_line
			(start 0.12065 0.2794)
			(end 0.12065 0.3048)
			(stroke
				(width 0.1)
				(type default)
			)
			(layer "B.Fab")
		)
		(fp_line
			(start -0.12065 -0.2794)
			(end -0.12065 -0.3048)
			(stroke
				(width 0.1)
				(type default)
			)
			(layer "B.Fab")
		)
		(fp_line
			(start 0.12065 -0.2794)
			(end -0.12065 -0.2794)
			(stroke
				(width 0.1)
				(type default)
			)
			(layer "B.Fab")
		)
		(fp_line
			(start -0.67945 -0.3048)
			(end -0.67945 0.3048)
			(stroke
				(width 0.1)
				(type default)
			)
			(layer "B.Fab")
		)
		(fp_line
			(start -0.12065 -0.3048)
			(end -0.67945 -0.3048)
			(stroke
				(width 0.1)
				(type default)
			)
			(layer "B.Fab")
		)
		(fp_line
			(start 0.12065 -0.305054)
			(end 0.12065 -0.2794)
			(stroke
				(width 0.1)
				(type default)
			)
			(layer "B.Fab")
		)
		(fp_line
			(start 0.67945 -0.305054)
			(end 0.12065 -0.305054)
			(stroke
				(width 0.1)
				(type default)
			)
			(layer "B.Fab")
		)
		(pad "1" smd circle
			(at 0.40005 0 90)
			(size 0 0)
			(layers "B.Cu" "B.Mask" "B.Paste")
			(net "SMB_NIC0_SCL")
		)
		(pad "2" smd circle
			(at -0.40005 0 90)
			(size 0 0)
			(layers "B.Cu" "B.Mask" "B.Paste")
			(net "SMB_NIC0_R_SCL")
		)
	)
)
